# BASEBOARD_FAB2 (Tioga Pass) — schematic netlist excerpt (pin names and nets, part order shuffled) for the footprints in the layout excerpt that follows; sources: Cadence DE-HDL packaged netlist, KiCad conversion of Wiwynn_Tioga_Pass_MB.brd

C9R3  CAPP  470UF 2.5V 20% ALUM  pkg 3018  page 208 : A = PVCCIN_CPU1 ; B = GND
R2U45  RES  0.0 5% EMPTY  pkg 0402  page 152 : A = H_CPU1_MEMKLM_MEMHOT_LVT3_N ; B = H_CPU1_MEMKLM_MEMHOT_PCH_N
R1R6  RES  3.32K 1% EMPTY  pkg 0402  page 140 : A = SPI_NIC_MOSI ; B = GND

(kicad_pcb
	(version 20260206)
	(generator "pcbnew")
	(generator_version "10.0")
	(general
		(thickness 1.6)
		(legacy_teardrops no)
	)
	(paper "A4")
	(title_block
		(title "Wiwynn_Tioga_Pass_MB.brd")
		(comment 1 "Tioga Pass / footprints 3375-3377 of 4770")
	)
	(layers
		(0 "F.Cu" signal "TOP")
		(4 "In1.Cu" signal "L2GND")
		(6 "In2.Cu" signal "L3")
		(8 "In3.Cu" signal "L4GND")
		(10 "In4.Cu" signal "L5")
		(12 "In5.Cu" signal "L6GND")
		(14 "In6.Cu" signal "L7VCC")
		(16 "In7.Cu" signal "L8VCC")
		(18 "In8.Cu" signal "L9GND")
		(20 "In9.Cu" signal "L10")
		(22 "In10.Cu" signal "L11GND")
		(24 "In11.Cu" signal "L12")
		(26 "In12.Cu" signal "L13GND")
		(2 "B.Cu" signal "BOTTOM")
		(9 "F.Adhes" user "F.Adhesive")
		(11 "B.Adhes" user "B.Adhesive")
		(13 "F.Paste" user "Package Geometry/Pastemask Top")
		(15 "B.Paste" user "Package Geometry/Pastemask Bottom")
		(5 "F.SilkS" user "Ref Des/Silkscreen Top")
		(7 "B.SilkS" user "Ref Des/Silkscreen Bottom")
		(1 "F.Mask" user "Board Geometry/Soldermask Top")
		(3 "B.Mask" user "Board Geometry/Soldermask Bottom")
		(17 "Dwgs.User" user "User.Drawings")
		(19 "Cmts.User" user "User.Comments")
		(21 "Eco1.User" user "User.Eco1")
		(23 "Eco2.User" user "User.Eco2")
		(25 "Edge.Cuts" user "Board Geometry/Outline")
		(27 "Margin" user)
		(31 "F.CrtYd" user "Package Geometry/Place Bound Top")
		(29 "B.CrtYd" user "Package Geometry/Place Bound Bottom")
		(35 "F.Fab" user "Ref Des/Assembly Top")
		(33 "B.Fab" user "Ref Des/Assembly Bottom")
	)
	(footprint ""
		(layer "B.Cu")
		(at 413.5755 -17.526 -90)
		(property "Reference" "R2U45"
			(at 0 0 90)
			(layer "B.SilkS")
			(hide yes)
			(effects
				(font
					(size 1.27 1.27)
				)
				(justify mirror)
			)
		)
		(property "Value" ""
			(at 0 0 90)
			(layer "B.Fab")
			(effects
				(font
					(size 1.27 1.27)
				)
				(justify mirror)
			)
		)
		(duplicate_pad_numbers_are_jumpers no)
		(fp_poly
			(pts
				(xy 0.2794 -0.1016) (xy -0.2794 -0.1016) (xy -0.2794 0.9906) (xy 0.2794 0.9906)
			)
			(stroke
				(width 0)
				(type default)
			)
			(fill no)
			(layer "B.CrtYd")
		)
		(fp_line
			(start -0.2794 0.9906)
			(end -0.2794 -0.1016)
			(stroke
				(width 0.1)
				(type default)
			)
			(layer "B.Fab")
		)
		(fp_line
			(start 0.2794 0.9906)
			(end -0.2794 0.9906)
			(stroke
				(width 0.1)
				(type default)
			)
			(layer "B.Fab")
		)
		(fp_line
			(start -0.2794 -0.1016)
			(end 0.2794 -0.1016)
			(stroke
				(width 0.1)
				(type default)
			)
			(layer "B.Fab")
		)
		(fp_line
			(start 0.2794 -0.1016)
			(end 0.2794 0.9906)
			(stroke
				(width 0.1)
				(type default)
			)
			(layer "B.Fab")
		)
		(pad "1" smd rect
			(at 0 0 90)
			(size 0.508 0.508)
			(layers "B.Cu" "B.Mask" "B.Paste")
			(net "H_CPU1_MEMKLM_MEMHOT_LVT3_N")
		)
		(pad "2" smd rect
			(at 0 0.889 90)
			(size 0.508 0.508)
			(layers "B.Cu" "B.Mask" "B.Paste")
			(net "H_CPU1_MEMKLM_MEMHOT_PCH_N")
		)
		(zone
			(layer "B.Cu")
			(hatch none 0.5)
			(connect_pads
				(clearance 0)
			)
			(min_thickness 0.25)
			(keepout
				(tracks not_allowed)
				(vias allowed)
				(pads allowed)
				(copperpour not_allowed)
				(footprints allowed)
			)
			(placement
				(enabled no)
				(sheetname "")
			)
			(fill
				(thermal_gap 0.5)
				(thermal_bridge_width 0.5)
				(island_removal_mode 0)
			)
			(polygon
				(pts
					(xy 412.9405 -17.272) (xy 412.9405 -17.78) (xy 413.3215 -17.78) (xy 413.3215 -17.272)
				)
			)
		)
		(zone
			(layer "B.Cu")
			(hatch none 0.5)
			(connect_pads
				(clearance 0)
			)
			(min_thickness 0.25)
			(keepout
				(tracks allowed)
				(vias not_allowed)
				(pads allowed)
				(copperpour not_allowed)
				(footprints allowed)
			)
			(placement
				(enabled no)
				(sheetname "")
			)
			(fill
				(thermal_gap 0.5)
				(thermal_bridge_width 0.5)
				(island_removal_mode 0)
			)
			(polygon
				(pts
					(xy 413.3215 -17.272) (xy 413.3215 -17.78) (xy 412.9405 -17.78) (xy 412.9405 -17.272)
				)
			)
		)
	)
	(footprint ""
		(layer "B.Cu")
		(at 45.212 -62.611 -90)
		(property "Reference" "C9R3"
			(at -1.75133 -3.429 0)
			(unlocked yes)
			(layer "B.SilkS")
			(effects
				(font
					(size 0.7874 0.5842)
					(thickness 0.1524)
				)
				(justify mirror)
			)
		)
		(property "Value" ""
			(at 0 0 90)
			(layer "B.Fab")
			(effects
				(font
					(size 1.27 1.27)
				)
				(justify mirror)
			)
		)
		(duplicate_pad_numbers_are_jumpers no)
		(fp_line
			(start -2.286 7.366)
			(end -1.600708 7.366)
			(stroke
				(width 0.1524)
				(type default)
			)
			(layer "B.SilkS")
		)
		(fp_line
			(start -2.286 7.366)
			(end -2.286 1.63195)
			(stroke
				(width 0.1524)
				(type default)
			)
			(layer "B.SilkS")
		)
		(fp_line
			(start 2.286 7.366)
			(end 1.60147 7.366)
			(stroke
				(width 0.1524)
				(type default)
			)
			(layer "B.SilkS")
		)
		(fp_line
			(start 2.286 7.366)
			(end 2.286 1.632712)
			(stroke
				(width 0.1524)
				(type default)
			)
			(layer "B.SilkS")
		)
		(fp_line
			(start -2.504948 1.633728)
			(end -1.6002 1.633728)
			(stroke
				(width 0.1524)
				(type default)
			)
			(layer "B.SilkS")
		)
		(fp_line
			(start 2.563114 1.633728)
			(end 1.6002 1.633728)
			(stroke
				(width 0.1524)
				(type default)
			)
			(layer "B.SilkS")
		)
		(fp_line
			(start -2.504948 -1.616456)
			(end -2.504948 1.633728)
			(stroke
				(width 0.1524)
				(type default)
			)
			(layer "B.SilkS")
		)
		(fp_line
			(start -1.6002 -1.616456)
			(end -2.504948 -1.616456)
			(stroke
				(width 0.1524)
				(type default)
			)
			(layer "B.SilkS")
		)
		(fp_line
			(start 1.6002 -1.616456)
			(end 2.563114 -1.616456)
			(stroke
				(width 0.1524)
				(type default)
			)
			(layer "B.SilkS")
		)
		(fp_line
			(start 2.563114 -1.616456)
			(end 2.563114 1.633728)
			(stroke
				(width 0.1524)
				(type default)
			)
			(layer "B.SilkS")
		)
		(fp_rect
			(start 2.286 7.366)
			(end -2.286 -0.254)
			(stroke
				(width 0)
				(type default)
			)
			(fill no)
			(layer "B.CrtYd")
		)
		(fp_line
			(start -2.286 7.366)
			(end 2.286 7.366)
			(stroke
				(width 0.1)
				(type default)
			)
			(layer "B.Fab")
		)
		(fp_line
			(start 2.286 7.366)
			(end 2.286 -0.254)
			(stroke
				(width 0.1)
				(type default)
			)
			(layer "B.Fab")
		)
		(fp_line
			(start -2.286 -0.254)
			(end -2.286 7.366)
			(stroke
				(width 0.1)
				(type default)
			)
			(layer "B.Fab")
		)
		(fp_line
			(start 2.286 -0.254)
			(end -2.286 -0.254)
			(stroke
				(width 0.1)
				(type default)
			)
			(layer "B.Fab")
		)
		(pad "1" smd rect
			(at 0 0 90)
			(size 2.54 3.048)
			(layers "B.Cu" "B.Mask" "B.Paste")
			(net "PVCCIN_CPU1")
		)
		(pad "2" smd rect
			(at 0 7.112 90)
			(size 2.54 3.048)
			(layers "B.Cu" "B.Mask" "B.Paste")
			(net "GND")
		)
	)
	(footprint ""
		(layer "B.Cu")
		(at 487.160062 -28.4226 180)
		(property "Reference" "R1R6"
			(at 0.8382 -0.67818 180)
			(unlocked yes)
			(layer "B.SilkS")
			(effects
				(font
					(size 0.4064 0.254)
					(thickness 0.1524)
				)
				(justify left mirror)
			)
		)
		(property "Value" ""
			(at 0 0 0)
			(layer "B.Fab")
			(effects
				(font
					(size 1.27 1.27)
				)
				(justify mirror)
			)
		)
		(duplicate_pad_numbers_are_jumpers no)
		(fp_poly
			(pts
				(xy 0.2794 -0.1016) (xy -0.2794 -0.1016) (xy -0.2794 0.9906) (xy 0.2794 0.9906)
			)
			(stroke
				(width 0)
				(type default)
			)
			(fill no)
			(layer "B.CrtYd")
		)
		(fp_line
			(start 0.2794 0.9906)
			(end -0.2794 0.9906)
			(stroke
				(width 0.1)
				(type default)
			)
			(layer "B.Fab")
		)
		(fp_line
			(start 0.2794 -0.1016)
			(end 0.2794 0.9906)
			(stroke
				(width 0.1)
				(type default)
			)
			(layer "B.Fab")
		)
		(fp_line
			(start -0.2794 0.9906)
			(end -0.2794 -0.1016)
			(stroke
				(width 0.1)
				(type default)
			)
			(layer "B.Fab")
		)
		(fp_line
			(start -0.2794 -0.1016)
			(end 0.2794 -0.1016)
			(stroke
				(width 0.1)
				(type default)
			)
			(layer "B.Fab")
		)
		(pad "1" smd rect
			(at 0 0)
			(size 0.508 0.508)
			(layers "B.Cu" "B.Mask" "B.Paste")
			(net "SPI_NIC_MOSI")
		)
		(pad "2" smd rect
			(at 0 0.889)
			(size 0.508 0.508)
			(layers "B.Cu" "B.Mask" "B.Paste")
			(net "GND")
		)
		(zone
			(layer "B.Cu")
			(hatch none 0.5)
			(connect_pads
				(clearance 0)
			)
			(min_thickness 0.25)
			(keepout
				(tracks not_allowed)
				(vias allowed)
				(pads allowed)
				(copperpour not_allowed)
				(footprints allowed)
			)
			(placement
				(enabled no)
				(sheetname "")
			)
			(fill
				(thermal_gap 0.5)
				(thermal_bridge_width 0.5)
				(island_removal_mode 0)
			)
			(polygon
				(pts
					(xy 486.906062 -29.0576) (xy 487.414062 -29.0576) (xy 487.414062 -28.6766) (xy 486.906062 -28.6766)
				)
			)
		)
		(zone
			(layer "B.Cu")
			(hatch none 0.5)
			(connect_pads
				(clearance 0)
			)
			(min_thickness 0.25)
			(keepout
				(tracks allowed)
				(vias not_allowed)
				(pads allowed)
				(copperpour not_allowed)
				(footprints allowed)
			)
			(placement
				(enabled no)
				(sheetname "")
			)
			(fill
				(thermal_gap 0.5)
				(thermal_bridge_width 0.5)
				(island_removal_mode 0)
			)
			(polygon
				(pts
					(xy 486.906062 -28.6766) (xy 487.414062 -28.6766) (xy 487.414062 -29.0576) (xy 486.906062 -29.0576)
				)
			)
		)
	)
)
